# T6G (Grand Teton) — schematic netlist excerpt (pin names and nets, part order shuffled) for the footprints in the layout excerpt that follows; sources: Cadence DE-HDL packaged netlist, KiCad conversion of 04192023_DAF0TMB3IC0_F0TG_MB_C_brd_V02_OCP.brd

C2652  Q_CAP  22UF 4V 20% X6S  pkg C0402  page 70 : A = PVDD11_S3_P0 ; B = GND
C6113  Q_CAP  0.01UF 50V 10% X7R  pkg C0402  page 179 : A = P1V2_CPU0_USB2_DVDD12 ; B = GND

(kicad_pcb
	(version 20260206)
	(generator "pcbnew")
	(generator_version "10.0")
	(general
		(thickness 1.6)
		(legacy_teardrops no)
	)
	(paper "A4")
	(title_block
		(title "04192023_DAF0TMB3IC0_F0TG_MB_C_brd_V02_OCP.brd")
		(comment 1 "Grand Teton / footprints 6721-6722 of 8354")
	)
	(layers
		(0 "F.Cu" signal "TOP")
		(4 "In1.Cu" signal "GND")
		(6 "In2.Cu" signal "IN1")
		(8 "In3.Cu" signal "GND1")
		(10 "In4.Cu" signal "IN2")
		(12 "In5.Cu" signal "GND2")
		(14 "In6.Cu" signal "IN3")
		(16 "In7.Cu" signal "GND3")
		(18 "In8.Cu" signal "VCC")
		(20 "In9.Cu" signal "VCC1")
		(22 "In10.Cu" signal "GND4")
		(24 "In11.Cu" signal "IN4")
		(26 "In12.Cu" signal "GND5")
		(28 "In13.Cu" signal "IN5")
		(30 "In14.Cu" signal "GND6")
		(32 "In15.Cu" signal "IN6")
		(34 "In16.Cu" signal "GND7")
		(2 "B.Cu" signal "BOTTOM")
		(9 "F.Adhes" user "F.Adhesive")
		(11 "B.Adhes" user "B.Adhesive")
		(13 "F.Paste" user "Package Geometry/Pastemask Top")
		(15 "B.Paste" user "Package Geometry/Pastemask Bottom")
		(5 "F.SilkS" user "Ref Des/Silkscreen Top")
		(7 "B.SilkS" user "Ref Des/Silkscreen Bottom")
		(1 "F.Mask" user "Board Geometry/Soldermask Top")
		(3 "B.Mask" user "Board Geometry/Soldermask Bottom")
		(17 "Dwgs.User" user "User.Drawings")
		(19 "Cmts.User" user "User.Comments")
		(21 "Eco1.User" user "User.Eco1")
		(23 "Eco2.User" user "User.Eco2")
		(25 "Edge.Cuts" user "Board Geometry/Outline")
		(27 "Margin" user)
		(31 "F.CrtYd" user "Package Geometry/Place Bound Top")
		(29 "B.CrtYd" user "Package Geometry/Place Bound Bottom")
		(35 "F.Fab" user "Ref Des/Assembly Top")
		(33 "B.Fab" user "Ref Des/Assembly Bottom")
	)
	(footprint ""
		(layer "B.Cu")
		(at 113.841022 -27.04846)
		(property "Reference" "C6113"
			(at 0 0 0)
			(layer "B.SilkS")
			(hide yes)
			(effects
				(font
					(size 1.27 1.27)
				)
				(justify mirror)
			)
		)
		(property "Value" ""
			(at 0 0 0)
			(layer "B.Fab")
			(effects
				(font
					(size 1.27 1.27)
				)
				(justify mirror)
			)
		)
		(duplicate_pad_numbers_are_jumpers no)
		(fp_line
			(start -0.7874 -0.4064)
			(end -0.7874 0.4064)
			(stroke
				(width 0.1524)
				(type default)
			)
			(layer "B.SilkS")
		)
		(fp_line
			(start -0.7874 0.4064)
			(end 0.7874 0.4064)
			(stroke
				(width 0.1524)
				(type default)
			)
			(layer "B.SilkS")
		)
		(fp_line
			(start 0.7874 -0.4064)
			(end -0.7874 -0.4064)
			(stroke
				(width 0.1524)
				(type default)
			)
			(layer "B.SilkS")
		)
		(fp_line
			(start 0.7874 0.4064)
			(end 0.7874 -0.4064)
			(stroke
				(width 0.1524)
				(type default)
			)
			(layer "B.SilkS")
		)
		(fp_line
			(start -0.67945 -0.3048)
			(end -0.67945 0.3048)
			(stroke
				(width 0.1)
				(type default)
			)
			(layer "B.Fab")
		)
		(fp_line
			(start -0.67945 0.3048)
			(end -0.120396 0.3048)
			(stroke
				(width 0.1)
				(type default)
			)
			(layer "B.Fab")
		)
		(fp_line
			(start -0.12065 -0.3048)
			(end -0.67945 -0.3048)
			(stroke
				(width 0.1)
				(type default)
			)
			(layer "B.Fab")
		)
		(fp_line
			(start -0.12065 -0.2794)
			(end -0.12065 -0.3048)
			(stroke
				(width 0.1)
				(type default)
			)
			(layer "B.Fab")
		)
		(fp_line
			(start -0.120396 0.2794)
			(end 0.12065 0.2794)
			(stroke
				(width 0.1)
				(type default)
			)
			(layer "B.Fab")
		)
		(fp_line
			(start -0.120396 0.3048)
			(end -0.120396 0.2794)
			(stroke
				(width 0.1)
				(type default)
			)
			(layer "B.Fab")
		)
		(fp_line
			(start 0.12065 -0.305054)
			(end 0.12065 -0.2794)
			(stroke
				(width 0.1)
				(type default)
			)
			(layer "B.Fab")
		)
		(fp_line
			(start 0.12065 -0.2794)
			(end -0.12065 -0.2794)
			(stroke
				(width 0.1)
				(type default)
			)
			(layer "B.Fab")
		)
		(fp_line
			(start 0.12065 0.2794)
			(end 0.12065 0.3048)
			(stroke
				(width 0.1)
				(type default)
			)
			(layer "B.Fab")
		)
		(fp_line
			(start 0.12065 0.3048)
			(end 0.67945 0.3048)
			(stroke
				(width 0.1)
				(type default)
			)
			(layer "B.Fab")
		)
		(fp_line
			(start 0.67945 -0.305054)
			(end 0.12065 -0.305054)
			(stroke
				(width 0.1)
				(type default)
			)
			(layer "B.Fab")
		)
		(fp_line
			(start 0.67945 0.3048)
			(end 0.67945 -0.305054)
			(stroke
				(width 0.1)
				(type default)
			)
			(layer "B.Fab")
		)
		(pad "1" smd circle
			(at 0.40005 0 180)
			(size 0 0)
			(layers "B.Cu" "B.Mask" "B.Paste")
			(net "P1V2_CPU0_USB2_DVDD12")
		)
		(pad "2" smd circle
			(at -0.40005 0 180)
			(size 0 0)
			(layers "B.Cu" "B.Mask" "B.Paste")
			(net "GND")
		)
	)
	(footprint ""
		(layer "B.Cu")
		(at 371.297454 -266.00531)
		(property "Reference" "C2652"
			(at 0 0 0)
			(layer "B.SilkS")
			(hide yes)
			(effects
				(font
					(size 1.27 1.27)
				)
				(justify mirror)
			)
		)
		(property "Value" ""
			(at 0 0 0)
			(layer "B.Fab")
			(effects
				(font
					(size 1.27 1.27)
				)
				(justify mirror)
			)
		)
		(duplicate_pad_numbers_are_jumpers no)
		(fp_line
			(start -0.7874 -0.4064)
			(end -0.7874 0.4064)
			(stroke
				(width 0.1524)
				(type default)
			)
			(layer "B.SilkS")
		)
		(fp_line
			(start -0.7874 0.4064)
			(end 0.7874 0.4064)
			(stroke
				(width 0.1524)
				(type default)
			)
			(layer "B.SilkS")
		)
		(fp_line
			(start 0.7874 -0.4064)
			(end -0.7874 -0.4064)
			(stroke
				(width 0.1524)
				(type default)
			)
			(layer "B.SilkS")
		)
		(fp_line
			(start 0.7874 0.4064)
			(end 0.7874 -0.4064)
			(stroke
				(width 0.1524)
				(type default)
			)
			(layer "B.SilkS")
		)
		(fp_line
			(start -0.67945 -0.3048)
			(end -0.67945 0.3048)
			(stroke
				(width 0.1)
				(type default)
			)
			(layer "B.Fab")
		)
		(fp_line
			(start -0.67945 0.3048)
			(end -0.120396 0.3048)
			(stroke
				(width 0.1)
				(type default)
			)
			(layer "B.Fab")
		)
		(fp_line
			(start -0.12065 -0.3048)
			(end -0.67945 -0.3048)
			(stroke
				(width 0.1)
				(type default)
			)
			(layer "B.Fab")
		)
		(fp_line
			(start -0.12065 -0.2794)
			(end -0.12065 -0.3048)
			(stroke
				(width 0.1)
				(type default)
			)
			(layer "B.Fab")
		)
		(fp_line
			(start -0.120396 0.2794)
			(end 0.12065 0.2794)
			(stroke
				(width 0.1)
				(type default)
			)
			(layer "B.Fab")
		)
		(fp_line
			(start -0.120396 0.3048)
			(end -0.120396 0.2794)
			(stroke
				(width 0.1)
				(type default)
			)
			(layer "B.Fab")
		)
		(fp_line
			(start 0.12065 -0.305054)
			(end 0.12065 -0.2794)
			(stroke
				(width 0.1)
				(type default)
			)
			(layer "B.Fab")
		)
		(fp_line
			(start 0.12065 -0.2794)
			(end -0.12065 -0.2794)
			(stroke
				(width 0.1)
				(type default)
			)
			(layer "B.Fab")
		)
		(fp_line
			(start 0.12065 0.2794)
			(end 0.12065 0.3048)
			(stroke
				(width 0.1)
				(type default)
			)
			(layer "B.Fab")
		)
		(fp_line
			(start 0.12065 0.3048)
			(end 0.67945 0.3048)
			(stroke
				(width 0.1)
				(type default)
			)
			(layer "B.Fab")
		)
		(fp_line
			(start 0.67945 -0.305054)
			(end 0.12065 -0.305054)
			(stroke
				(width 0.1)
				(type default)
			)
			(layer "B.Fab")
		)
		(fp_line
			(start 0.67945 0.3048)
			(end 0.67945 -0.305054)
			(stroke
				(width 0.1)
				(type default)
			)
			(layer "B.Fab")
		)
		(pad "1" smd circle
			(at 0.40005 0 180)
			(size 0 0)
			(layers "B.Cu" "B.Mask" "B.Paste")
			(net "PVDD11_S3_P0")
		)
		(pad "2" smd circle
			(at -0.40005 0 180)
			(size 0 0)
			(layers "B.Cu" "B.Mask" "B.Paste")
			(net "GND")
		)
	)
)
